FILE_TYPE = MACRO_DRAWING;
SET COLOR_WIRE YELLOW;
SET COLOR_PROP ORANGE;
SET COLOR_DOT WHITE;
SET COLOR_ARC YELLOW;
SET COLOR_BODY GREEN;
SET COLOR_NOTE PURPLE;
SET PROP_DISPLAY VALUE;
SET PAGE_NUMBER P263;
FORCEADD QUANTA_TITLE_BLOCK_C..1
(9550 250);
FORCEPROP 1 LAST CUSTOM_TXT_CDS <NAME_2>
J 0
(6375 300);
FORCEPROP 1 LAST CUSTOM_TXT_CDS <NAME_1>
J 0
(6375 425);
FORCEPROP 1 LAST CUSTOM_TXT_CDS <Q_NUMBER>
J 0
(8147 353);
DISPLAY 1.212766 (8147 353);
FORCEPROP 1 LAST CUSTOM_TXT_CDS <Q_PROJ>
J 0
(7168 352);
DISPLAY 1.212766 (7168 352);
FORCEPROP 1 LAST CUSTOM_TXT_CDS <Q_REV>
J 0
(9366 353);
DISPLAY 1.212766 (9366 353);
FORCEPROP 1 LAST CUSTOM_TXT_CDS <CON_LAST_MODIFIED>
J 0
(7665 265);
DISPLAY 0.978723 (7665 265);
FORCEPROP 1 LAST CUSTOM_TXT_CDS <CON_PAGE_NUM> OF <CON_TOTAL_PAGES>
J 0
(9104 268);
DISPLAY 0.978723 (9104 268);
FORCEPROP 1 LAST Q_TITLE BLANK
J 0
(184 276);
DISPLAY 2.446809 (184 276);
PAINT GREEN (184 276);
FORCEPROP 1 LAST Q_DEPT 
J 1
(5787 299);
DISPLAY 1.957447 (5787 299);
PAINT GREEN (5787 299);
FORCEPROP 2 LAST CDS_XR_PAGE_TITLE CR-277 : @S9S_MB_2U_LIB.S9S_MB_2U(SCH_1):PAGE277
J 0
(1660 5500);
DISPLAY 0.638298 (1660 5500);
PAINT PINK (1660 5500);
DISPLAY INVISIBLE (1660 5500);
FORCEPROP 1 LAST COMMENT_BODY TRUE
J 0
(9562 237);
DISPLAY 0.978723 (9562 237);
PAINT GREEN (9562 237);
DISPLAY INVISIBLE (9562 237);
FORCEPROP 2 LAST CDS_LIB pure_quanta
J 0
(9550 250);
DISPLAY INVISIBLE (9550 250);
FORCEPROP 1 LAST CDS_LMAN_SYM_OUTLINE -9475,6775,100,-125
J 0
(9550 250);
DISPLAY 0.468085 (9550 250);
PAINT GREEN (9550 250);
DISPLAY INVISIBLE (9550 250);
FORCEPROP 2 LAST PAGE_BORDER TRUE
J 0
(1660 5500);
DISPLAY 0.638298 (1660 5500);
PAINT PINK (1660 5500);
DISPLAY INVISIBLE (1660 5500);
FORCEPROP 2 LAST CUSTOM_TXT_CDS <XR_PAGE_TITLE>
J 0
(1660 5500);
DISPLAY 0.638298 (1660 5500);
PAINT PINK (1660 5500);
DISPLAY INVISIBLE (1660 5500);
FORCEPROP 0 LAST CDS_CON_LAST_MODIFIED Thu Aug 24 16:16:38 2023
J 0
(7665 265);
DISPLAY INVISIBLE (7665 265);
QUIT
